# ZAIUS-LV CARD-DVT-X01-BOM-X00_20170420_Final.xls.xlsx — DEPOP (bom)
| FOXCONN TECHNOLOGY GROUP |  |  |  |  |  |  |  |  |  |  |  |  |
| BILL OF MATERIAL |  |  |  |  |  |  |  |  |  |  |  |  |
| REV OF  BOM | X00 | CUSTOMER | Customer |  | CUSTOMER P/N |  | PRODUCT CODE |  | PWA  REV | X01 | DATE | 42845 |
| Sourcing (Single/Sole/Multi) | Critical Commodity (Y or N) | Component Class (1, 2, other) | Customer PSL (Y or N) | Item Number | Foxconn P/N | Customer P/N | Part Description | Manufacturer  Full Name | Manufacturer  Part Number | Qty | RoHS Status | Location |
|  | N | ND | N | 1 | 610107A00-017-G | - | RES,0 Ohm,+/-5%,1/16W,G,SMD0402 | KOA SPEER ELECTRONICS, INC. | RK73Z1ETTP | 10 | N | R1,R3,R4,R5,R7,R8,R9,R10,R11,R12 |
